(kicad_pcb
	(version 20260206)
	(generator "pcbnew")
	(generator_version "10.0")
	(general
		(thickness 1.6)
		(legacy_teardrops no)
	)
	(paper "A4")
	(title_block
		(title "01162023_DA0F0TEBIF0_F0T_Expander_BD_F_brd_V02_OCP.brd")
		(comment 1 "Grand Teton / footprints 6275-6281 of 9728")
	)
	(layers
		(0 "F.Cu" signal "TOP")
		(4 "In1.Cu" signal "GND")
		(6 "In2.Cu" signal "VCC")
		(8 "In3.Cu" signal "VCC1")
		(10 "In4.Cu" signal "GND1")
		(12 "In5.Cu" signal "IN1")
		(14 "In6.Cu" signal "GND2")
		(16 "In7.Cu" signal "IN2")
		(18 "In8.Cu" signal "GND3")
		(20 "In9.Cu" signal "IN3")
		(22 "In10.Cu" signal "GND4")
		(24 "In11.Cu" signal "IN4")
		(26 "In12.Cu" signal "GND5")
		(28 "In13.Cu" signal "IN5")
		(30 "In14.Cu" signal "GND6")
		(32 "In15.Cu" signal "IN6")
		(34 "In16.Cu" signal "GND7")
		(2 "B.Cu" signal "BOTTOM")
		(9 "F.Adhes" user "F.Adhesive")
		(11 "B.Adhes" user "B.Adhesive")
		(13 "F.Paste" user "Package Geometry/Pastemask Top")
		(15 "B.Paste" user "Package Geometry/Pastemask Bottom")
		(5 "F.SilkS" user "Ref Des/Silkscreen Top")
		(7 "B.SilkS" user "Ref Des/Silkscreen Bottom")
		(1 "F.Mask" user "Board Geometry/Soldermask Top")
		(3 "B.Mask" user "Board Geometry/Soldermask Bottom")
		(17 "Dwgs.User" user "User.Drawings")
		(19 "Cmts.User" user "User.Comments")
		(21 "Eco1.User" user "User.Eco1")
		(23 "Eco2.User" user "User.Eco2")
		(25 "Edge.Cuts" user "Board Geometry/Outline")
		(27 "Margin" user)
		(31 "F.CrtYd" user "Package Geometry/Place Bound Top")
		(29 "B.CrtYd" user "Package Geometry/Place Bound Bottom")
		(35 "F.Fab" user "Ref Des/Assembly Top")
		(33 "B.Fab" user "Ref Des/Assembly Bottom")
	)
	(footprint ""
		(layer "F.Cu")
		(at 179.570634 -138.864848)
		(property "Reference" "R193"
			(at 0 0 0)
			(layer "F.SilkS")
			(hide yes)
			(effects
				(font
					(size 1.27 1.27)
				)
			)
		)
		(property "Value" ""
			(at 0 0 0)
			(layer "F.Fab")
			(effects
				(font
					(size 1.27 1.27)
				)
			)
		)
		(duplicate_pad_numbers_are_jumpers no)
		(fp_line
			(start -0.7874 -0.4064)
			(end 0.7874 -0.4064)
			(stroke
				(width 0.1524)
				(type default)
			)
			(layer "F.SilkS")
		)
		(fp_line
			(start -0.7874 0.4064)
			(end -0.7874 -0.4064)
			(stroke
				(width 0.1524)
				(type default)
			)
			(layer "F.SilkS")
		)
		(fp_line
			(start 0.7874 -0.4064)
			(end 0.7874 0.4064)
			(stroke
				(width 0.1524)
				(type default)
			)
			(layer "F.SilkS")
		)
		(fp_line
			(start 0.7874 0.4064)
			(end -0.7874 0.4064)
			(stroke
				(width 0.1524)
				(type default)
			)
			(layer "F.SilkS")
		)
		(fp_line
			(start -0.67945 -0.305054)
			(end -0.12065 -0.305054)
			(stroke
				(width 0.1)
				(type default)
			)
			(layer "F.Fab")
		)
		(fp_line
			(start -0.67945 0.3048)
			(end -0.67945 -0.305054)
			(stroke
				(width 0.1)
				(type default)
			)
			(layer "F.Fab")
		)
		(fp_line
			(start -0.12065 -0.305054)
			(end -0.12065 -0.2794)
			(stroke
				(width 0.1)
				(type default)
			)
			(layer "F.Fab")
		)
		(fp_line
			(start -0.12065 -0.2794)
			(end 0.12065 -0.2794)
			(stroke
				(width 0.1)
				(type default)
			)
			(layer "F.Fab")
		)
		(fp_line
			(start -0.12065 0.2794)
			(end -0.12065 0.3048)
			(stroke
				(width 0.1)
				(type default)
			)
			(layer "F.Fab")
		)
		(fp_line
			(start -0.12065 0.3048)
			(end -0.67945 0.3048)
			(stroke
				(width 0.1)
				(type default)
			)
			(layer "F.Fab")
		)
		(fp_line
			(start 0.120396 0.2794)
			(end -0.12065 0.2794)
			(stroke
				(width 0.1)
				(type default)
			)
			(layer "F.Fab")
		)
		(fp_line
			(start 0.120396 0.3048)
			(end 0.120396 0.2794)
			(stroke
				(width 0.1)
				(type default)
			)
			(layer "F.Fab")
		)
		(fp_line
			(start 0.12065 -0.3048)
			(end 0.67945 -0.3048)
			(stroke
				(width 0.1)
				(type default)
			)
			(layer "F.Fab")
		)
		(fp_line
			(start 0.12065 -0.2794)
			(end 0.12065 -0.3048)
			(stroke
				(width 0.1)
				(type default)
			)
			(layer "F.Fab")
		)
		(fp_line
			(start 0.67945 -0.3048)
			(end 0.67945 0.3048)
			(stroke
				(width 0.1)
				(type default)
			)
			(layer "F.Fab")
		)
		(fp_line
			(start 0.67945 0.3048)
			(end 0.120396 0.3048)
			(stroke
				(width 0.1)
				(type default)
			)
			(layer "F.Fab")
		)
		(pad "1" smd circle
			(at -0.40005 0)
			(size 0 0)
			(layers "F.Cu" "F.Mask" "F.Paste")
			(net "PRSNT_NIC3_N")
		)
		(pad "2" smd circle
			(at 0.40005 0)
			(size 0 0)
			(layers "F.Cu" "F.Mask" "F.Paste")
			(net "PRSNTB1_NIC3_N")
		)
	)
	(footprint ""
		(layer "F.Cu")
		(at 331.131164 -356.244906 90)
		(property "Reference" "C569"
			(at 0 0 90)
			(layer "F.SilkS")
			(hide yes)
			(effects
				(font
					(size 1.27 1.27)
				)
			)
		)
		(property "Value" ""
			(at 0 0 90)
			(layer "F.Fab")
			(effects
				(font
					(size 1.27 1.27)
				)
			)
		)
		(duplicate_pad_numbers_are_jumpers no)
		(fp_line
			(start 0.299974 -0.150114)
			(end 0.299974 0.150114)
			(stroke
				(width 0.1)
				(type default)
			)
			(layer "F.Fab")
		)
		(fp_line
			(start -0.299974 -0.150114)
			(end 0.299974 -0.150114)
			(stroke
				(width 0.1)
				(type default)
			)
			(layer "F.Fab")
		)
		(fp_line
			(start 0.299974 0.150114)
			(end -0.299974 0.150114)
			(stroke
				(width 0.1)
				(type default)
			)
			(layer "F.Fab")
		)
		(fp_line
			(start -0.299974 0.150114)
			(end -0.299974 -0.150114)
			(stroke
				(width 0.1)
				(type default)
			)
			(layer "F.Fab")
		)
		(pad "1" smd rect
			(at -0.2667 0 90)
			(size 0.3048 0.381)
			(layers "F.Cu" "F.Mask" "F.Paste")
			(net "P5E_PEX2_STN6_TX_DP<102>")
		)
		(pad "2" smd rect
			(at 0.2667 0 90)
			(size 0.3048 0.381)
			(layers "F.Cu" "F.Mask" "F.Paste")
			(net "P5E_PEX2_STN6_TX_C_DP<102>")
		)
	)
	(footprint ""
		(layer "F.Cu")
		(at 316.775592 -36.915598 -90)
		(property "Reference" "R5583"
			(at 0 0 270)
			(layer "F.SilkS")
			(hide yes)
			(effects
				(font
					(size 1.27 1.27)
				)
			)
		)
		(property "Value" ""
			(at 0 0 270)
			(layer "F.Fab")
			(effects
				(font
					(size 1.27 1.27)
				)
			)
		)
		(duplicate_pad_numbers_are_jumpers no)
		(fp_line
			(start -0.7874 0.4064)
			(end -0.7874 -0.4064)
			(stroke
				(width 0.1524)
				(type default)
			)
			(layer "F.SilkS")
		)
		(fp_line
			(start 0.7874 0.4064)
			(end -0.7874 0.4064)
			(stroke
				(width 0.1524)
				(type default)
			)
			(layer "F.SilkS")
		)
		(fp_line
			(start -0.7874 -0.4064)
			(end 0.7874 -0.4064)
			(stroke
				(width 0.1524)
				(type default)
			)
			(layer "F.SilkS")
		)
		(fp_line
			(start 0.7874 -0.4064)
			(end 0.7874 0.4064)
			(stroke
				(width 0.1524)
				(type default)
			)
			(layer "F.SilkS")
		)
		(fp_line
			(start -0.67945 0.3048)
			(end -0.67945 -0.305054)
			(stroke
				(width 0.1)
				(type default)
			)
			(layer "F.Fab")
		)
		(fp_line
			(start -0.12065 0.3048)
			(end -0.67945 0.3048)
			(stroke
				(width 0.1)
				(type default)
			)
			(layer "F.Fab")
		)
		(fp_line
			(start 0.120396 0.3048)
			(end 0.120396 0.2794)
			(stroke
				(width 0.1)
				(type default)
			)
			(layer "F.Fab")
		)
		(fp_line
			(start 0.67945 0.3048)
			(end 0.120396 0.3048)
			(stroke
				(width 0.1)
				(type default)
			)
			(layer "F.Fab")
		)
		(fp_line
			(start -0.12065 0.2794)
			(end -0.12065 0.3048)
			(stroke
				(width 0.1)
				(type default)
			)
			(layer "F.Fab")
		)
		(fp_line
			(start 0.120396 0.2794)
			(end -0.12065 0.2794)
			(stroke
				(width 0.1)
				(type default)
			)
			(layer "F.Fab")
		)
		(fp_line
			(start -0.12065 -0.2794)
			(end 0.12065 -0.2794)
			(stroke
				(width 0.1)
				(type default)
			)
			(layer "F.Fab")
		)
		(fp_line
			(start 0.12065 -0.2794)
			(end 0.12065 -0.3048)
			(stroke
				(width 0.1)
				(type default)
			)
			(layer "F.Fab")
		)
		(fp_line
			(start 0.12065 -0.3048)
			(end 0.67945 -0.3048)
			(stroke
				(width 0.1)
				(type default)
			)
			(layer "F.Fab")
		)
		(fp_line
			(start 0.67945 -0.3048)
			(end 0.67945 0.3048)
			(stroke
				(width 0.1)
				(type default)
			)
			(layer "F.Fab")
		)
		(fp_line
			(start -0.67945 -0.305054)
			(end -0.12065 -0.305054)
			(stroke
				(width 0.1)
				(type default)
			)
			(layer "F.Fab")
		)
		(fp_line
			(start -0.12065 -0.305054)
			(end -0.12065 -0.2794)
			(stroke
				(width 0.1)
				(type default)
			)
			(layer "F.Fab")
		)
		(pad "1" smd circle
			(at -0.40005 0 270)
			(size 0 0)
			(layers "F.Cu" "F.Mask" "F.Paste")
			(net "PRSNT_SSD11_R1_N")
		)
		(pad "2" smd circle
			(at 0.40005 0 270)
			(size 0 0)
			(layers "F.Cu" "F.Mask" "F.Paste")
			(net "PRSNT_SSD11_R_N")
		)
	)
	(footprint ""
		(layer "F.Cu")
		(at 3.630168 -24.945594 90)
		(property "Reference" "R1639"
			(at 0 0 90)
			(layer "F.SilkS")
			(hide yes)
			(effects
				(font
					(size 1.27 1.27)
				)
			)
		)
		(property "Value" ""
			(at 0 0 90)
			(layer "F.Fab")
			(effects
				(font
					(size 1.27 1.27)
				)
			)
		)
		(duplicate_pad_numbers_are_jumpers no)
		(fp_line
			(start 0.7874 -0.4064)
			(end 0.7874 0.4064)
			(stroke
				(width 0.1524)
				(type default)
			)
			(layer "F.SilkS")
		)
		(fp_line
			(start -0.7874 -0.4064)
			(end 0.7874 -0.4064)
			(stroke
				(width 0.1524)
				(type default)
			)
			(layer "F.SilkS")
		)
		(fp_line
			(start 0.7874 0.4064)
			(end -0.7874 0.4064)
			(stroke
				(width 0.1524)
				(type default)
			)
			(layer "F.SilkS")
		)
		(fp_line
			(start -0.7874 0.4064)
			(end -0.7874 -0.4064)
			(stroke
				(width 0.1524)
				(type default)
			)
			(layer "F.SilkS")
		)
		(fp_line
			(start -0.12065 -0.305054)
			(end -0.12065 -0.2794)
			(stroke
				(width 0.1)
				(type default)
			)
			(layer "F.Fab")
		)
		(fp_line
			(start -0.67945 -0.305054)
			(end -0.12065 -0.305054)
			(stroke
				(width 0.1)
				(type default)
			)
			(layer "F.Fab")
		)
		(fp_line
			(start 0.67945 -0.3048)
			(end 0.67945 0.3048)
			(stroke
				(width 0.1)
				(type default)
			)
			(layer "F.Fab")
		)
		(fp_line
			(start 0.12065 -0.3048)
			(end 0.67945 -0.3048)
			(stroke
				(width 0.1)
				(type default)
			)
			(layer "F.Fab")
		)
		(fp_line
			(start 0.12065 -0.2794)
			(end 0.12065 -0.3048)
			(stroke
				(width 0.1)
				(type default)
			)
			(layer "F.Fab")
		)
		(fp_line
			(start -0.12065 -0.2794)
			(end 0.12065 -0.2794)
			(stroke
				(width 0.1)
				(type default)
			)
			(layer "F.Fab")
		)
		(fp_line
			(start 0.120396 0.2794)
			(end -0.12065 0.2794)
			(stroke
				(width 0.1)
				(type default)
			)
			(layer "F.Fab")
		)
		(fp_line
			(start -0.12065 0.2794)
			(end -0.12065 0.3048)
			(stroke
				(width 0.1)
				(type default)
			)
			(layer "F.Fab")
		)
		(fp_line
			(start 0.67945 0.3048)
			(end 0.120396 0.3048)
			(stroke
				(width 0.1)
				(type default)
			)
			(layer "F.Fab")
		)
		(fp_line
			(start 0.120396 0.3048)
			(end 0.120396 0.2794)
			(stroke
				(width 0.1)
				(type default)
			)
			(layer "F.Fab")
		)
		(fp_line
			(start -0.12065 0.3048)
			(end -0.67945 0.3048)
			(stroke
				(width 0.1)
				(type default)
			)
			(layer "F.Fab")
		)
		(fp_line
			(start -0.67945 0.3048)
			(end -0.67945 -0.305054)
			(stroke
				(width 0.1)
				(type default)
			)
			(layer "F.Fab")
		)
		(pad "1" smd circle
			(at -0.40005 0 90)
			(size 0 0)
			(layers "F.Cu" "F.Mask" "F.Paste")
			(net "SMB_ISO_SSD0_R_SDA")
		)
		(pad "2" smd circle
			(at 0.40005 0 90)
			(size 0 0)
			(layers "F.Cu" "F.Mask" "F.Paste")
			(net "SMB_ISO_SSD0_SDA")
		)
	)
	(footprint ""
		(layer "F.Cu")
		(at 411.97784 -116.550186 180)
		(property "Reference" "R364"
			(at 0 0 180)
			(layer "F.SilkS")
			(hide yes)
			(effects
				(font
					(size 1.27 1.27)
				)
			)
		)
		(property "Value" ""
			(at 0 0 180)
			(layer "F.Fab")
			(effects
				(font
					(size 1.27 1.27)
				)
			)
		)
		(duplicate_pad_numbers_are_jumpers no)
		(fp_line
			(start 0.7874 0.4064)
			(end -0.7874 0.4064)
			(stroke
				(width 0.1524)
				(type default)
			)
			(layer "F.SilkS")
		)
		(fp_line
			(start 0.7874 -0.4064)
			(end 0.7874 0.4064)
			(stroke
				(width 0.1524)
				(type default)
			)
			(layer "F.SilkS")
		)
		(fp_line
			(start -0.7874 0.4064)
			(end -0.7874 -0.4064)
			(stroke
				(width 0.1524)
				(type default)
			)
			(layer "F.SilkS")
		)
		(fp_line
			(start -0.7874 -0.4064)
			(end 0.7874 -0.4064)
			(stroke
				(width 0.1524)
				(type default)
			)
			(layer "F.SilkS")
		)
		(fp_line
			(start 0.67945 0.3048)
			(end 0.120396 0.3048)
			(stroke
				(width 0.1)
				(type default)
			)
			(layer "F.Fab")
		)
		(fp_line
			(start 0.67945 -0.3048)
			(end 0.67945 0.3048)
			(stroke
				(width 0.1)
				(type default)
			)
			(layer "F.Fab")
		)
		(fp_line
			(start 0.12065 -0.2794)
			(end 0.12065 -0.3048)
			(stroke
				(width 0.1)
				(type default)
			)
			(layer "F.Fab")
		)
		(fp_line
			(start 0.12065 -0.3048)
			(end 0.67945 -0.3048)
			(stroke
				(width 0.1)
				(type default)
			)
			(layer "F.Fab")
		)
		(fp_line
			(start 0.120396 0.3048)
			(end 0.120396 0.2794)
			(stroke
				(width 0.1)
				(type default)
			)
			(layer "F.Fab")
		)
		(fp_line
			(start 0.120396 0.2794)
			(end -0.12065 0.2794)
			(stroke
				(width 0.1)
				(type default)
			)
			(layer "F.Fab")
		)
		(fp_line
			(start -0.12065 0.3048)
			(end -0.67945 0.3048)
			(stroke
				(width 0.1)
				(type default)
			)
			(layer "F.Fab")
		)
		(fp_line
			(start -0.12065 0.2794)
			(end -0.12065 0.3048)
			(stroke
				(width 0.1)
				(type default)
			)
			(layer "F.Fab")
		)
		(fp_line
			(start -0.12065 -0.2794)
			(end 0.12065 -0.2794)
			(stroke
				(width 0.1)
				(type default)
			)
			(layer "F.Fab")
		)
		(fp_line
			(start -0.12065 -0.305054)
			(end -0.12065 -0.2794)
			(stroke
				(width 0.1)
				(type default)
			)
			(layer "F.Fab")
		)
		(fp_line
			(start -0.67945 0.3048)
			(end -0.67945 -0.305054)
			(stroke
				(width 0.1)
				(type default)
			)
			(layer "F.Fab")
		)
		(fp_line
			(start -0.67945 -0.305054)
			(end -0.12065 -0.305054)
			(stroke
				(width 0.1)
				(type default)
			)
			(layer "F.Fab")
		)
		(pad "1" smd circle
			(at -0.40005 0 180)
			(size 0 0)
			(layers "F.Cu" "F.Mask" "F.Paste")
			(net "PRSNTB2_NIC7_N")
		)
		(pad "2" smd circle
			(at 0.40005 0 180)
			(size 0 0)
			(layers "F.Cu" "F.Mask" "F.Paste")
			(net "P3V3_AUX")
		)
	)
	(footprint ""
		(layer "F.Cu")
		(at 339.598 -201.168 -90)
		(property "Reference" "R4140"
			(at 0 0 270)
			(layer "F.SilkS")
			(hide yes)
			(effects
				(font
					(size 1.27 1.27)
				)
			)
		)
		(property "Value" ""
			(at 0 0 270)
			(layer "F.Fab")
			(effects
				(font
					(size 1.27 1.27)
				)
			)
		)
		(duplicate_pad_numbers_are_jumpers no)
		(fp_line
			(start -0.7874 0.4064)
			(end -0.7874 -0.4064)
			(stroke
				(width 0.1524)
				(type default)
			)
			(layer "F.SilkS")
		)
		(fp_line
			(start 0.7874 0.4064)
			(end -0.7874 0.4064)
			(stroke
				(width 0.1524)
				(type default)
			)
			(layer "F.SilkS")
		)
		(fp_line
			(start -0.7874 -0.4064)
			(end 0.7874 -0.4064)
			(stroke
				(width 0.1524)
				(type default)
			)
			(layer "F.SilkS")
		)
		(fp_line
			(start 0.7874 -0.4064)
			(end 0.7874 0.4064)
			(stroke
				(width 0.1524)
				(type default)
			)
			(layer "F.SilkS")
		)
		(fp_line
			(start -0.67945 0.3048)
			(end -0.67945 -0.305054)
			(stroke
				(width 0.1)
				(type default)
			)
			(layer "F.Fab")
		)
		(fp_line
			(start -0.12065 0.3048)
			(end -0.67945 0.3048)
			(stroke
				(width 0.1)
				(type default)
			)
			(layer "F.Fab")
		)
		(fp_line
			(start 0.120396 0.3048)
			(end 0.120396 0.2794)
			(stroke
				(width 0.1)
				(type default)
			)
			(layer "F.Fab")
		)
		(fp_line
			(start 0.67945 0.3048)
			(end 0.120396 0.3048)
			(stroke
				(width 0.1)
				(type default)
			)
			(layer "F.Fab")
		)
		(fp_line
			(start -0.12065 0.2794)
			(end -0.12065 0.3048)
			(stroke
				(width 0.1)
				(type default)
			)
			(layer "F.Fab")
		)
		(fp_line
			(start 0.120396 0.2794)
			(end -0.12065 0.2794)
			(stroke
				(width 0.1)
				(type default)
			)
			(layer "F.Fab")
		)
		(fp_line
			(start -0.12065 -0.2794)
			(end 0.12065 -0.2794)
			(stroke
				(width 0.1)
				(type default)
			)
			(layer "F.Fab")
		)
		(fp_line
			(start 0.12065 -0.2794)
			(end 0.12065 -0.3048)
			(stroke
				(width 0.1)
				(type default)
			)
			(layer "F.Fab")
		)
		(fp_line
			(start 0.12065 -0.3048)
			(end 0.67945 -0.3048)
			(stroke
				(width 0.1)
				(type default)
			)
			(layer "F.Fab")
		)
		(fp_line
			(start 0.67945 -0.3048)
			(end 0.67945 0.3048)
			(stroke
				(width 0.1)
				(type default)
			)
			(layer "F.Fab")
		)
		(fp_line
			(start -0.67945 -0.305054)
			(end -0.12065 -0.305054)
			(stroke
				(width 0.1)
				(type default)
			)
			(layer "F.Fab")
		)
		(fp_line
			(start -0.12065 -0.305054)
			(end -0.12065 -0.2794)
			(stroke
				(width 0.1)
				(type default)
			)
			(layer "F.Fab")
		)
		(pad "1" smd circle
			(at -0.40005 0 270)
			(size 0 0)
			(layers "F.Cu" "F.Mask" "F.Paste")
			(net "SSD14_PWRDIS")
		)
		(pad "2" smd circle
			(at 0.40005 0 270)
			(size 0 0)
			(layers "F.Cu" "F.Mask" "F.Paste")
			(net "SSD14_PWRDIS_R")
		)
	)
	(footprint ""
		(layer "F.Cu")
		(at 216.480136 -179.848256 -90)
		(property "Reference" "R5418"
			(at 0 0 270)
			(layer "F.SilkS")
			(hide yes)
			(effects
				(font
					(size 1.27 1.27)
				)
			)
		)
		(property "Value" ""
			(at 0 0 270)
			(layer "F.Fab")
			(effects
				(font
					(size 1.27 1.27)
				)
			)
		)
		(duplicate_pad_numbers_are_jumpers no)
		(fp_line
			(start -0.7874 0.4064)
			(end -0.7874 -0.4064)
			(stroke
				(width 0.1524)
				(type default)
			)
			(layer "F.SilkS")
		)
		(fp_line
			(start 0.7874 0.4064)
			(end -0.7874 0.4064)
			(stroke
				(width 0.1524)
				(type default)
			)
			(layer "F.SilkS")
		)
		(fp_line
			(start -0.7874 -0.4064)
			(end 0.7874 -0.4064)
			(stroke
				(width 0.1524)
				(type default)
			)
			(layer "F.SilkS")
		)
		(fp_line
			(start 0.7874 -0.4064)
			(end 0.7874 0.4064)
			(stroke
				(width 0.1524)
				(type default)
			)
			(layer "F.SilkS")
		)
		(fp_line
			(start -0.67945 0.3048)
			(end -0.67945 -0.305054)
			(stroke
				(width 0.1)
				(type default)
			)
			(layer "F.Fab")
		)
		(fp_line
			(start -0.12065 0.3048)
			(end -0.67945 0.3048)
			(stroke
				(width 0.1)
				(type default)
			)
			(layer "F.Fab")
		)
		(fp_line
			(start 0.120396 0.3048)
			(end 0.120396 0.2794)
			(stroke
				(width 0.1)
				(type default)
			)
			(layer "F.Fab")
		)
		(fp_line
			(start 0.67945 0.3048)
			(end 0.120396 0.3048)
			(stroke
				(width 0.1)
				(type default)
			)
			(layer "F.Fab")
		)
		(fp_line
			(start -0.12065 0.2794)
			(end -0.12065 0.3048)
			(stroke
				(width 0.1)
				(type default)
			)
			(layer "F.Fab")
		)
		(fp_line
			(start 0.120396 0.2794)
			(end -0.12065 0.2794)
			(stroke
				(width 0.1)
				(type default)
			)
			(layer "F.Fab")
		)
		(fp_line
			(start -0.12065 -0.2794)
			(end 0.12065 -0.2794)
			(stroke
				(width 0.1)
				(type default)
			)
			(layer "F.Fab")
		)
		(fp_line
			(start 0.12065 -0.2794)
			(end 0.12065 -0.3048)
			(stroke
				(width 0.1)
				(type default)
			)
			(layer "F.Fab")
		)
		(fp_line
			(start 0.12065 -0.3048)
			(end 0.67945 -0.3048)
			(stroke
				(width 0.1)
				(type default)
			)
			(layer "F.Fab")
		)
		(fp_line
			(start 0.67945 -0.3048)
			(end 0.67945 0.3048)
			(stroke
				(width 0.1)
				(type default)
			)
			(layer "F.Fab")
		)
		(fp_line
			(start -0.67945 -0.305054)
			(end -0.12065 -0.305054)
			(stroke
				(width 0.1)
				(type default)
			)
			(layer "F.Fab")
		)
		(fp_line
			(start -0.12065 -0.305054)
			(end -0.12065 -0.2794)
			(stroke
				(width 0.1)
				(type default)
			)
			(layer "F.Fab")
		)
		(pad "1" smd circle
			(at -0.40005 0 270)
			(size 0 0)
			(layers "F.Cu" "F.Mask" "F.Paste")
			(net "SEL_FLASH_PEX0_BUF_R")
		)
		(pad "2" smd circle
			(at 0.40005 0 270)
			(size 0 0)
			(layers "F.Cu" "F.Mask" "F.Paste")
			(net "P3V3_AUX")
		)
	)
)
